(kicad_pcb
	(version 20260206)
	(generator "pcbnew")
	(generator_version "10.0")
	(general
		(thickness 1.6)
		(legacy_teardrops no)
	)
	(paper "A4")
	(title_block
		(title "Wiwynn_Tioga_Pass_MB.brd")
		(comment 1 "Tioga Pass / footprints 1452-1459 of 4770")
	)
	(layers
		(0 "F.Cu" signal "TOP")
		(4 "In1.Cu" signal "L2GND")
		(6 "In2.Cu" signal "L3")
		(8 "In3.Cu" signal "L4GND")
		(10 "In4.Cu" signal "L5")
		(12 "In5.Cu" signal "L6GND")
		(14 "In6.Cu" signal "L7VCC")
		(16 "In7.Cu" signal "L8VCC")
		(18 "In8.Cu" signal "L9GND")
		(20 "In9.Cu" signal "L10")
		(22 "In10.Cu" signal "L11GND")
		(24 "In11.Cu" signal "L12")
		(26 "In12.Cu" signal "L13GND")
		(2 "B.Cu" signal "BOTTOM")
		(9 "F.Adhes" user "F.Adhesive")
		(11 "B.Adhes" user "B.Adhesive")
		(13 "F.Paste" user "Package Geometry/Pastemask Top")
		(15 "B.Paste" user "Package Geometry/Pastemask Bottom")
		(5 "F.SilkS" user "Ref Des/Silkscreen Top")
		(7 "B.SilkS" user "Ref Des/Silkscreen Bottom")
		(1 "F.Mask" user "Board Geometry/Soldermask Top")
		(3 "B.Mask" user "Board Geometry/Soldermask Bottom")
		(17 "Dwgs.User" user "User.Drawings")
		(19 "Cmts.User" user "User.Comments")
		(21 "Eco1.User" user "User.Eco1")
		(23 "Eco2.User" user "User.Eco2")
		(25 "Edge.Cuts" user "Board Geometry/Outline")
		(27 "Margin" user)
		(31 "F.CrtYd" user "Package Geometry/Place Bound Top")
		(29 "B.CrtYd" user "Package Geometry/Place Bound Bottom")
		(35 "F.Fab" user "Ref Des/Assembly Top")
		(33 "B.Fab" user "Ref Des/Assembly Bottom")
	)
	(footprint ""
		(layer "F.Cu")
		(at 366.154716 -147.914106)
		(property "Reference" "C7W5"
			(at 0 0 0)
			(layer "F.SilkS")
			(hide yes)
			(effects
				(font
					(size 1.27 1.27)
				)
			)
		)
		(property "Value" "*"
			(at -0.0762 -6.2357 0)
			(unlocked yes)
			(layer "F.Fab")
			(hide yes)
			(effects
				(font
					(size 1.27 1.016)
					(thickness 0.1524)
				)
			)
		)
		(property "Device Type" "SC22U16V5MX-4-GP_SMD-BCG5-SC22A"
			(at -0.0762 -8.2677 0)
			(unlocked yes)
			(layer "F.Fab")
			(hide yes)
			(effects
				(font
					(size 1.27 1.016)
					(thickness 0.1524)
				)
			)
		)
		(duplicate_pad_numbers_are_jumpers no)
		(fp_line
			(start 0.635 0)
			(end -0.635 0)
			(stroke
				(width 0.508)
				(type default)
			)
			(layer "F.SilkS")
		)
		(fp_rect
			(start -0.9652 1.778)
			(end 0.9652 -1.778)
			(stroke
				(width 0)
				(type default)
			)
			(fill no)
			(layer "F.CrtYd")
		)
		(fp_poly
			(pts
				(xy -0.9652 -1.778) (xy 0.9652 -1.778) (xy 0.9652 1.778) (xy -0.9652 1.778)
			)
			(stroke
				(width 0)
				(type default)
			)
			(fill no)
			(layer "F.Fab")
		)
		(pad "1" smd rect
			(at 0 -0.9652)
			(size 1.397 1.143)
			(layers "F.Cu" "F.Mask" "F.Paste")
			(net "VR_FET_SW_P12V_STBY_PVDDQ_DEF")
		)
		(pad "2" smd rect
			(at 0 0.9652)
			(size 1.397 1.143)
			(layers "F.Cu" "F.Mask" "F.Paste")
			(net "GND")
		)
	)
	(footprint ""
		(layer "F.Cu")
		(at 466.476842 -25.77846 -90)
		(property "Reference" "R8E34"
			(at 0 0 270)
			(layer "F.SilkS")
			(hide yes)
			(effects
				(font
					(size 1.27 1.27)
				)
			)
		)
		(property "Value" ""
			(at 0 0 270)
			(layer "F.Fab")
			(effects
				(font
					(size 1.27 1.27)
				)
			)
		)
		(duplicate_pad_numbers_are_jumpers no)
		(fp_rect
			(start 0.2794 -0.1016)
			(end -0.2794 0.9906)
			(stroke
				(width 0)
				(type default)
			)
			(fill no)
			(layer "F.CrtYd")
		)
		(fp_line
			(start -0.2794 0.9906)
			(end 0.2794 0.9906)
			(stroke
				(width 0.1)
				(type default)
			)
			(layer "F.Fab")
		)
		(fp_line
			(start 0.2794 0.9906)
			(end 0.2794 -0.1016)
			(stroke
				(width 0.1)
				(type default)
			)
			(layer "F.Fab")
		)
		(fp_line
			(start -0.2794 -0.1016)
			(end -0.2794 0.9906)
			(stroke
				(width 0.1)
				(type default)
			)
			(layer "F.Fab")
		)
		(fp_line
			(start 0.2794 -0.1016)
			(end -0.2794 -0.1016)
			(stroke
				(width 0.1)
				(type default)
			)
			(layer "F.Fab")
		)
		(pad "1" smd rect
			(at 0 0 270)
			(size 0.508 0.508)
			(layers "F.Cu" "F.Mask" "F.Paste")
			(net "VSENSE_VOUT_P3V3_STBY")
		)
		(pad "2" smd rect
			(at 0 0.889 270)
			(size 0.508 0.508)
			(layers "F.Cu" "F.Mask" "F.Paste")
			(net "AGND_P3V3_STBY")
		)
		(zone
			(layer "F.Cu")
			(hatch none 0.5)
			(connect_pads
				(clearance 0)
			)
			(min_thickness 0.25)
			(keepout
				(tracks not_allowed)
				(vias allowed)
				(pads allowed)
				(copperpour not_allowed)
				(footprints allowed)
			)
			(placement
				(enabled no)
				(sheetname "")
			)
			(fill
				(thermal_gap 0.5)
				(thermal_bridge_width 0.5)
				(island_removal_mode 0)
			)
			(polygon
				(pts
					(xy 466.222842 -25.52446) (xy 466.222842 -26.03246) (xy 465.841842 -26.03246) (xy 465.841842 -25.52446)
				)
			)
		)
		(zone
			(layer "F.Cu")
			(hatch none 0.5)
			(connect_pads
				(clearance 0)
			)
			(min_thickness 0.25)
			(keepout
				(tracks allowed)
				(vias not_allowed)
				(pads allowed)
				(copperpour not_allowed)
				(footprints allowed)
			)
			(placement
				(enabled no)
				(sheetname "")
			)
			(fill
				(thermal_gap 0.5)
				(thermal_bridge_width 0.5)
				(island_removal_mode 0)
			)
			(polygon
				(pts
					(xy 466.222842 -25.52446) (xy 466.222842 -26.03246) (xy 465.841842 -26.03246) (xy 465.841842 -25.52446)
				)
			)
		)
	)
	(footprint ""
		(layer "F.Cu")
		(at 389.60679 -157.493462 -90)
		(property "Reference" "C7A44"
			(at 0 0 270)
			(layer "F.SilkS")
			(hide yes)
			(effects
				(font
					(size 1.27 1.27)
				)
			)
		)
		(property "Value" ""
			(at 0 0 270)
			(layer "F.Fab")
			(effects
				(font
					(size 1.27 1.27)
				)
			)
		)
		(duplicate_pad_numbers_are_jumpers no)
		(fp_poly
			(pts
				(xy 0.3048 -0.1016) (xy 0.3048 0.9906) (xy -0.3048 0.9906) (xy -0.3048 -0.1016)
			)
			(stroke
				(width 0)
				(type default)
			)
			(fill no)
			(layer "F.CrtYd")
		)
		(fp_line
			(start -0.3048 0.9906)
			(end 0.3048 0.9906)
			(stroke
				(width 0.1)
				(type default)
			)
			(layer "F.Fab")
		)
		(fp_line
			(start 0.3048 0.9906)
			(end 0.3048 -0.1016)
			(stroke
				(width 0.1)
				(type default)
			)
			(layer "F.Fab")
		)
		(fp_line
			(start -0.3048 -0.1016)
			(end -0.3048 0.9906)
			(stroke
				(width 0.1)
				(type default)
			)
			(layer "F.Fab")
		)
		(fp_line
			(start 0.3048 -0.1016)
			(end -0.3048 -0.1016)
			(stroke
				(width 0.1)
				(type default)
			)
			(layer "F.Fab")
		)
		(pad "1" smd rect
			(at 0 0 270)
			(size 0.508 0.508)
			(layers "F.Cu" "F.Mask" "F.Paste")
			(net "VR_P1V05_PCH_STBY_PH1_BOOT")
		)
		(pad "2" smd rect
			(at 0 0.889 270)
			(size 0.508 0.508)
			(layers "F.Cu" "F.Mask" "F.Paste")
			(net "VR_P1V05_PCH_STBY_PH1_PHASE")
		)
		(zone
			(layer "F.Cu")
			(hatch none 0.5)
			(connect_pads
				(clearance 0)
			)
			(min_thickness 0.25)
			(keepout
				(tracks not_allowed)
				(vias allowed)
				(pads allowed)
				(copperpour not_allowed)
				(footprints allowed)
			)
			(placement
				(enabled no)
				(sheetname "")
			)
			(fill
				(thermal_gap 0.5)
				(thermal_bridge_width 0.5)
				(island_removal_mode 0)
			)
			(polygon
				(pts
					(xy 388.97179 -157.747462) (xy 388.97179 -157.239462) (xy 389.35279 -157.239462) (xy 389.35279 -157.747462)
				)
			)
		)
		(zone
			(layer "F.Cu")
			(hatch none 0.5)
			(connect_pads
				(clearance 0)
			)
			(min_thickness 0.25)
			(keepout
				(tracks allowed)
				(vias not_allowed)
				(pads allowed)
				(copperpour not_allowed)
				(footprints allowed)
			)
			(placement
				(enabled no)
				(sheetname "")
			)
			(fill
				(thermal_gap 0.5)
				(thermal_bridge_width 0.5)
				(island_removal_mode 0)
			)
			(polygon
				(pts
					(xy 389.35279 -157.747462) (xy 389.35279 -157.239462) (xy 388.97179 -157.239462) (xy 388.97179 -157.747462)
				)
			)
		)
	)
	(footprint ""
		(layer "F.Cu")
		(at 418.973 -83.580986)
		(property "Reference" "U8D5"
			(at 3.27025 2.02692 90)
			(unlocked yes)
			(layer "F.SilkS")
			(effects
				(font
					(size 0.7874 0.5842)
					(thickness 0.1524)
				)
				(justify left)
			)
		)
		(property "Value" ""
			(at 0 0 0)
			(layer "F.Fab")
			(effects
				(font
					(size 1.27 1.27)
				)
			)
		)
		(duplicate_pad_numbers_are_jumpers no)
		(fp_circle
			(center -0.4699 -0.8382)
			(end -0.3429 -0.8382)
			(stroke
				(width 0.254)
				(type default)
			)
			(fill no)
			(layer "F.SilkS")
		)
		(fp_poly
			(pts
				(xy 0.21463 -0.450088) (xy 1.56337 -0.450088) (xy 1.56337 1.75006) (xy 0.21463 1.75006)
			)
			(stroke
				(width 0)
				(type default)
			)
			(fill no)
			(layer "F.CrtYd")
		)
		(fp_line
			(start 0.21463 -0.450088)
			(end 1.56337 -0.450088)
			(stroke
				(width 0.1)
				(type default)
			)
			(layer "F.Fab")
		)
		(fp_line
			(start 0.21463 1.75006)
			(end 0.21463 -0.450088)
			(stroke
				(width 0.1)
				(type default)
			)
			(layer "F.Fab")
		)
		(fp_line
			(start 1.56337 -0.450088)
			(end 1.56337 1.75006)
			(stroke
				(width 0.1)
				(type default)
			)
			(layer "F.Fab")
		)
		(fp_line
			(start 1.56337 1.75006)
			(end 0.21463 1.75006)
			(stroke
				(width 0.1)
				(type default)
			)
			(layer "F.Fab")
		)
		(fp_circle
			(center -0.4699 -0.8382)
			(end -0.3429 -0.8382)
			(stroke
				(width 0.254)
				(type default)
			)
			(fill no)
			(layer "F.Fab")
		)
		(pad "1" smd rect
			(at 0 0)
			(size 1.016 0.381)
			(layers "F.Cu" "F.Mask" "F.Paste")
			(net "FM_PMBUS_ALERT_BUF_EN")
		)
		(pad "2" smd rect
			(at 0 0.649986)
			(size 1.016 0.381)
			(layers "F.Cu" "F.Mask" "F.Paste")
			(net "IRQ_SML1_PMBUS_ALERT_N")
		)
		(pad "3" smd rect
			(at 0 1.299972)
			(size 1.016 0.381)
			(layers "F.Cu" "F.Mask" "F.Paste")
			(net "GND")
		)
		(pad "4" smd rect
			(at 1.778 1.299972)
			(size 1.016 0.381)
			(layers "F.Cu" "F.Mask" "F.Paste")
			(net "IRQ_SML1_PMBUS_ALERT_BUF_N")
		)
		(pad "5" smd rect
			(at 1.778 0)
			(size 1.016 0.381)
			(layers "F.Cu" "F.Mask" "F.Paste")
			(net "P3V3_STBY")
		)
	)
	(footprint ""
		(layer "F.Cu")
		(at 269.75181 -84.890102)
		(property "Reference" "C5D2"
			(at 0 0 0)
			(layer "F.SilkS")
			(hide yes)
			(effects
				(font
					(size 1.27 1.27)
				)
			)
		)
		(property "Value" ""
			(at 0 0 0)
			(layer "F.Fab")
			(effects
				(font
					(size 1.27 1.27)
				)
			)
		)
		(duplicate_pad_numbers_are_jumpers no)
		(fp_poly
			(pts
				(xy -0.4953 -0.2032) (xy 0.4953 -0.2032) (xy 0.4953 1.6002) (xy -0.4953 1.6002)
			)
			(stroke
				(width 0)
				(type default)
			)
			(fill no)
			(layer "F.CrtYd")
		)
		(fp_line
			(start -0.4953 -0.2032)
			(end 0.4953 -0.2032)
			(stroke
				(width 0.1)
				(type default)
			)
			(layer "F.Fab")
		)
		(fp_line
			(start -0.4953 1.6002)
			(end -0.4953 -0.2032)
			(stroke
				(width 0.1)
				(type default)
			)
			(layer "F.Fab")
		)
		(fp_line
			(start 0.4953 -0.2032)
			(end 0.4953 1.6002)
			(stroke
				(width 0.1)
				(type default)
			)
			(layer "F.Fab")
		)
		(fp_line
			(start 0.4953 1.6002)
			(end -0.4953 1.6002)
			(stroke
				(width 0.1)
				(type default)
			)
			(layer "F.Fab")
		)
		(pad "1" smd rect
			(at 0 0)
			(size 0.762 0.889)
			(layers "F.Cu" "F.Mask" "F.Paste")
			(net "PVDDQ_DEF")
		)
		(pad "2" smd rect
			(at 0 1.397)
			(size 0.762 0.889)
			(layers "F.Cu" "F.Mask" "F.Paste")
			(net "GND")
		)
		(zone
			(layer "F.Cu")
			(hatch none 0.5)
			(connect_pads
				(clearance 0)
			)
			(min_thickness 0.25)
			(keepout
				(tracks not_allowed)
				(vias allowed)
				(pads allowed)
				(copperpour not_allowed)
				(footprints allowed)
			)
			(placement
				(enabled no)
				(sheetname "")
			)
			(fill
				(thermal_gap 0.5)
				(thermal_bridge_width 0.5)
				(island_removal_mode 0)
			)
			(polygon
				(pts
					(xy 269.37081 -84.445602) (xy 270.13281 -84.445602) (xy 270.13281 -83.937602) (xy 269.37081 -83.937602)
				)
			)
		)
	)
	(footprint ""
		(layer "F.Cu")
		(at 175.133 -7.8105 180)
		(property "Reference" "R4G13"
			(at 0 0 180)
			(layer "F.SilkS")
			(hide yes)
			(effects
				(font
					(size 1.27 1.27)
				)
			)
		)
		(property "Value" ""
			(at 0 0 180)
			(layer "F.Fab")
			(effects
				(font
					(size 1.27 1.27)
				)
			)
		)
		(duplicate_pad_numbers_are_jumpers no)
		(fp_rect
			(start 0.2794 -0.1016)
			(end -0.2794 0.9906)
			(stroke
				(width 0)
				(type default)
			)
			(fill no)
			(layer "F.CrtYd")
		)
		(fp_line
			(start 0.2794 0.9906)
			(end 0.2794 -0.1016)
			(stroke
				(width 0.1)
				(type default)
			)
			(layer "F.Fab")
		)
		(fp_line
			(start 0.2794 -0.1016)
			(end -0.2794 -0.1016)
			(stroke
				(width 0.1)
				(type default)
			)
			(layer "F.Fab")
		)
		(fp_line
			(start -0.2794 0.9906)
			(end 0.2794 0.9906)
			(stroke
				(width 0.1)
				(type default)
			)
			(layer "F.Fab")
		)
		(fp_line
			(start -0.2794 -0.1016)
			(end -0.2794 0.9906)
			(stroke
				(width 0.1)
				(type default)
			)
			(layer "F.Fab")
		)
		(pad "1" smd rect
			(at 0 0 180)
			(size 0.508 0.508)
			(layers "F.Cu" "F.Mask" "F.Paste")
			(net "VR_COMP_RC_PVPP_GHJ")
		)
		(pad "2" smd rect
			(at 0 0.889 180)
			(size 0.508 0.508)
			(layers "F.Cu" "F.Mask" "F.Paste")
			(net "VR_FB_PVPP_GHJ")
		)
		(zone
			(layer "F.Cu")
			(hatch none 0.5)
			(connect_pads
				(clearance 0)
			)
			(min_thickness 0.25)
			(keepout
				(tracks allowed)
				(vias not_allowed)
				(pads allowed)
				(copperpour not_allowed)
				(footprints allowed)
			)
			(placement
				(enabled no)
				(sheetname "")
			)
			(fill
				(thermal_gap 0.5)
				(thermal_bridge_width 0.5)
				(island_removal_mode 0)
			)
			(polygon
				(pts
					(xy 174.879 -8.0645) (xy 175.387 -8.0645) (xy 175.387 -8.4455) (xy 174.879 -8.4455)
				)
			)
		)
		(zone
			(layer "F.Cu")
			(hatch none 0.5)
			(connect_pads
				(clearance 0)
			)
			(min_thickness 0.25)
			(keepout
				(tracks not_allowed)
				(vias allowed)
				(pads allowed)
				(copperpour not_allowed)
				(footprints allowed)
			)
			(placement
				(enabled no)
				(sheetname "")
			)
			(fill
				(thermal_gap 0.5)
				(thermal_bridge_width 0.5)
				(island_removal_mode 0)
			)
			(polygon
				(pts
					(xy 174.879 -8.0645) (xy 175.387 -8.0645) (xy 175.387 -8.4455) (xy 174.879 -8.4455)
				)
			)
		)
	)
	(footprint ""
		(layer "F.Cu")
		(at 266.9286 -79.6036 180)
		(property "Reference" "C5D18"
			(at 0 0 180)
			(layer "F.SilkS")
			(hide yes)
			(effects
				(font
					(size 1.27 1.27)
				)
			)
		)
		(property "Value" ""
			(at 0 0 180)
			(layer "F.Fab")
			(effects
				(font
					(size 1.27 1.27)
				)
			)
		)
		(duplicate_pad_numbers_are_jumpers no)
		(fp_poly
			(pts
				(xy -0.4953 -0.2032) (xy 0.4953 -0.2032) (xy 0.4953 1.6002) (xy -0.4953 1.6002)
			)
			(stroke
				(width 0)
				(type default)
			)
			(fill no)
			(layer "F.CrtYd")
		)
		(fp_line
			(start 0.4953 1.6002)
			(end -0.4953 1.6002)
			(stroke
				(width 0.1)
				(type default)
			)
			(layer "F.Fab")
		)
		(fp_line
			(start 0.4953 -0.2032)
			(end 0.4953 1.6002)
			(stroke
				(width 0.1)
				(type default)
			)
			(layer "F.Fab")
		)
		(fp_line
			(start -0.4953 1.6002)
			(end -0.4953 -0.2032)
			(stroke
				(width 0.1)
				(type default)
			)
			(layer "F.Fab")
		)
		(fp_line
			(start -0.4953 -0.2032)
			(end 0.4953 -0.2032)
			(stroke
				(width 0.1)
				(type default)
			)
			(layer "F.Fab")
		)
		(pad "1" smd rect
			(at 0 0 180)
			(size 0.762 0.889)
			(layers "F.Cu" "F.Mask" "F.Paste")
			(net "PVCCIN_CPU0")
		)
		(pad "2" smd rect
			(at 0 1.397 180)
			(size 0.762 0.889)
			(layers "F.Cu" "F.Mask" "F.Paste")
			(net "GND")
		)
		(zone
			(layer "F.Cu")
			(hatch none 0.5)
			(connect_pads
				(clearance 0)
			)
			(min_thickness 0.25)
			(keepout
				(tracks not_allowed)
				(vias allowed)
				(pads allowed)
				(copperpour not_allowed)
				(footprints allowed)
			)
			(placement
				(enabled no)
				(sheetname "")
			)
			(fill
				(thermal_gap 0.5)
				(thermal_bridge_width 0.5)
				(island_removal_mode 0)
			)
			(polygon
				(pts
					(xy 267.3096 -80.0481) (xy 266.5476 -80.0481) (xy 266.5476 -80.5561) (xy 267.3096 -80.5561)
				)
			)
		)
	)
	(footprint ""
		(layer "F.Cu")
		(at 341.249 -98.425 180)
		(property "Reference" "L7C2"
			(at 3.378708 -4.251706 180)
			(unlocked yes)
			(layer "F.SilkS")
			(effects
				(font
					(size 0.4064 0.254)
					(thickness 0.1524)
				)
			)
		)
		(property "Value" ""
			(at 0 0 180)
			(layer "F.Fab")
			(effects
				(font
					(size 1.27 1.27)
				)
			)
		)
		(duplicate_pad_numbers_are_jumpers no)
		(fp_line
			(start 8.3693 3.199892)
			(end -1.1303 3.199892)
			(stroke
				(width 0.1524)
				(type default)
			)
			(layer "F.SilkS")
		)
		(fp_line
			(start 8.3693 1.6637)
			(end 8.3693 3.199892)
			(stroke
				(width 0.1524)
				(type default)
			)
			(layer "F.SilkS")
		)
		(fp_line
			(start 8.3693 -3.199892)
			(end 8.3693 -1.6637)
			(stroke
				(width 0.1524)
				(type default)
			)
			(layer "F.SilkS")
		)
		(fp_line
			(start -1.1303 3.199892)
			(end -1.1303 1.6637)
			(stroke
				(width 0.1524)
				(type default)
			)
			(layer "F.SilkS")
		)
		(fp_line
			(start -1.1303 -1.6637)
			(end -1.1303 -3.199892)
			(stroke
				(width 0.1524)
				(type default)
			)
			(layer "F.SilkS")
		)
		(fp_line
			(start -1.1303 -3.199892)
			(end 8.3693 -3.199892)
			(stroke
				(width 0.1524)
				(type default)
			)
			(layer "F.SilkS")
		)
		(fp_rect
			(start -1.1303 3.199892)
			(end 8.3693 -3.199892)
			(stroke
				(width 0)
				(type default)
			)
			(fill no)
			(layer "F.CrtYd")
		)
		(fp_line
			(start 8.3693 3.199892)
			(end -1.1303 3.199892)
			(stroke
				(width 0.1)
				(type default)
			)
			(layer "F.Fab")
		)
		(fp_line
			(start 8.3693 -3.199892)
			(end 8.3693 3.199892)
			(stroke
				(width 0.1)
				(type default)
			)
			(layer "F.Fab")
		)
		(fp_line
			(start -1.1303 3.199892)
			(end -1.1303 -3.199892)
			(stroke
				(width 0.1)
				(type default)
			)
			(layer "F.Fab")
		)
		(fp_line
			(start -1.1303 -3.199892)
			(end 8.3693 -3.199892)
			(stroke
				(width 0.1)
				(type default)
			)
			(layer "F.Fab")
		)
		(pad "1" smd rect
			(at 0 0 180)
			(size 3.683 2.667)
			(layers "F.Cu" "F.Mask" "F.Paste")
			(net "VR_PVCCIO_CPU0_PH1_SW")
		)
		(pad "2" smd rect
			(at 7.239 0 180)
			(size 3.683 2.667)
			(layers "F.Cu" "F.Mask" "F.Paste")
			(net "PVCCIO_CPU0")
		)
	)
)
